G04 ================== begin FILE IDENTIFICATION RECORD ==================*
G04 Layout Name:  14629-1a.brd*
G04 Film Name:    P_OUTLINE*
G04 File Format:  Gerber RS274X*
G04 File Origin:  Cadence Allegro 16.5-S037*
G04 Origin Date:  Tue Nov 25 11:50:32 2014*
G04 *
G04 Layer:  BOARD GEOMETRY/PANEL_OUTLINE*
G04 *
G04 Offset:    (0.00 0.00)*
G04 Mirror:    No*
G04 Mode:      Positive*
G04 Rotation:  0*
G04 FullContactRelief:  No*
G04 UndefLineWidth:     6.00*
G04 ================== end FILE IDENTIFICATION RECORD ====================*
%FSLAX35Y35*MOIN*%
%IR0*IPPOS*OFA0.00000B0.00000*MIA0B0*SFA1.00000B1.00000*%
%ADD10C,.006*%
G75*
%LPD*%
G75*
G54D10*
G01X-43308Y-5685D02*
G03X-29308Y-19685I14000J0D01*
G01X85820D02*
X-29308D01*
G01X0Y3937D02*
Y106969D01*
G01X636457Y0D02*
X3937D01*
G01X0Y3937D02*
G03X3937Y0I3937J0D01*
G01Y-7874D02*
X77283D01*
G01X-7874Y3937D02*
G03X3937Y-7874I11811J0D01*
G01X-7874Y50259D02*
Y3937D01*
G01X-43308Y-5685D02*
Y103032D01*
G01X0Y3937D02*
G03X3937Y0I3937J0D01*
G01X0Y3937D02*
G03X3937Y0I3937J0D01*
G01X636457D02*
X3937D01*
G01X636457D02*
X3937D01*
G01X0Y3937D02*
Y106969D01*
G01Y3937D02*
Y106969D01*
G01Y50259D02*
G03X-7874I-3937J0D01*
G01Y75460D02*
G03X0I3937J0D01*
G01X-7874Y103032D02*
Y75456D01*
G01X-43307Y286142D02*
Y116811D01*
G01D02*
X-37402Y110906D01*
G01D02*
X-3937D01*
G01X0Y106969D02*
G03X-3937Y110906I-3937J0D01*
G01X-43308Y103032D02*
X-7874D01*
G01X0Y106969D02*
G03X-3937Y110906I-3937J0D01*
G01X0Y106969D02*
G03X-3937Y110906I-3937J0D01*
G01X-37402D02*
X-3937D01*
G01X-37402D02*
X-3937D01*
G01X-41339Y114843D02*
X-37402Y110906D01*
G01X-43307Y116811D02*
X-37402Y110906D01*
G01X-43307Y286142D02*
Y116811D01*
G01Y360039D02*
Y300709D01*
G01X-37402Y292047D02*
X-43307Y286142D01*
G01Y300709D02*
X-37402Y294803D01*
G01Y292047D02*
X-1378D01*
G01X-37402Y294803D02*
X-1378D01*
G01Y292047D02*
G03Y294803I0J1378D01*
G01Y292047D02*
G03Y294803I0J1378D01*
G01Y292047D02*
G03Y294803I0J1378D01*
G01X-37402D02*
X-1378D01*
G01X-37402D02*
X-1378D01*
G01X-12598Y292047D02*
X-1378D01*
G01X-37402D02*
X-1378D01*
G01X-12598D02*
X-37402D01*
G01X-41339Y298740D02*
X-37402Y294803D01*
G01X-43307Y300709D02*
X-37402Y294803D01*
G01Y292047D02*
X-43307Y286142D01*
G01X-37402Y292047D02*
X-41339Y288110D01*
G01X-43307Y360039D02*
Y300709D01*
G01X-37402Y365945D02*
X-43307Y360039D01*
G01X0Y369882D02*
Y468504D01*
G01X-3937Y365945D02*
X-37402D01*
G01X-3937D02*
G03X0Y369882I0J3937D01*
G01X-43308Y373820D02*
Y583347D01*
G01X-43307Y373819D02*
X-43308Y373820D01*
G01X-7874Y373819D02*
X-43307D01*
G01X-7874Y401397D02*
Y373819D01*
G01X-3937Y365945D02*
G03X0Y369882I0J3937D01*
G01X-3937Y365945D02*
G03X0Y369882I0J3937D01*
G01X-3937Y365945D02*
X-37402D01*
G01X-3937D02*
X-37402D01*
G01X0Y369882D02*
Y468504D01*
G01Y369882D02*
Y468504D01*
G01X-37402Y365945D02*
X-43307Y360039D01*
G01X-37402Y365945D02*
X-41339Y362008D01*
G01X-7874Y426594D02*
Y530574D01*
G01Y426594D02*
G03X0I3937J0D01*
G01Y401397D02*
G03X-7874I-3937J0D01*
G01X3937Y472441D02*
X636457D01*
G01X3937D02*
G03X0Y468504I0J-3937D01*
G01Y484252D02*
G03X3937Y480315I3937J0D01*
G01X0Y484252D02*
G03X3937Y480315I3937J0D01*
G01X636457D02*
X3937D01*
G01X636457D02*
X3937D01*
G01X0Y484252D02*
Y587283D01*
G01Y484252D02*
Y587283D01*
G01X3937Y472441D02*
G03X0Y468504I0J-3937D01*
G01X3937Y472441D02*
G03X0Y468504I0J-3937D01*
G01X3937Y472441D02*
X636457D01*
G01X3937D02*
X636457D01*
G01X0Y530574D02*
G03X-7874I-3937J0D01*
G01Y555771D02*
G03X0I3937J0D01*
G01X-7874Y583347D02*
Y555771D01*
G01X-43308Y583347D02*
X-7874D01*
G01X0Y587283D02*
G03X-3937Y591220I-3937J0D01*
G01X0Y587283D02*
G03X-3937Y591220I-3937J0D01*
G01X-37402D02*
X-3937D01*
G01X-37402D02*
X-3937D01*
G01X-41339Y595157D02*
X-37402Y591220D01*
G01X-43307Y597126D02*
X-37402Y591220D01*
G01X-43307Y766457D02*
Y597126D01*
G01X-1378Y772362D02*
G03Y775118I0J1378D01*
G01Y772362D02*
G03Y775118I0J1378D01*
G01X-37402D02*
X-1378D01*
G01X-37402D02*
X-1378D01*
G01X-12598Y772362D02*
X-1378D01*
G01X-37402D02*
X-1378D01*
G01X-12598D02*
X-37402D01*
G01X-41339Y779055D02*
X-37402Y775118D01*
G01X-43307Y781024D02*
X-37402Y775118D01*
G01Y772362D02*
X-43307Y766457D01*
G01X-37402Y772362D02*
X-41339Y768425D01*
G01X-43307Y840354D02*
Y781024D01*
G01X-37402Y846260D02*
X-43307Y840354D01*
G01X-37402Y846260D02*
X-41339Y842323D01*
G01X0Y881711D02*
G03X-7874I-3937J0D01*
G01X-43308Y854134D02*
Y958441D01*
G01X-7874Y854134D02*
X-43308D01*
G01X-7874Y881712D02*
Y854134D01*
G01X-3937Y846260D02*
G03X0Y850197I0J3937D01*
G01X-3937Y846260D02*
G03X0Y850197I0J3937D01*
G01X-3937Y846260D02*
X-37402D01*
G01X-3937D02*
X-37402D01*
G01X0Y850197D02*
Y948819D01*
G01Y850197D02*
Y948819D01*
G01X3937Y960630D02*
G03X-7874Y948819I0J-11811D01*
G01Y906909D02*
Y948819D01*
G01Y906909D02*
G03X0I3937J0D01*
G01X-29308Y972441D02*
G03X-43308Y958441I0J-14000D01*
G01X3937Y952756D02*
G03X0Y948819I0J-3937D01*
G01X3937Y952756D02*
G03X0Y948819I0J-3937D01*
G01X3937Y952756D02*
X636457D01*
G01X3937D02*
X636457D01*
G01X3937Y960630D02*
X77283D01*
G01X-29308Y972441D02*
X1317968D01*
G01X93694Y-19685D02*
G03X85820I-3937J0D01*
G01X93694D02*
X1317968D01*
G01X77283Y-7874D02*
G03Y0I0J3937D01*
G01X107993D02*
G03Y-7874I0J-3937D01*
G01D02*
X304843D01*
G01X77283Y472441D02*
G03Y480315I0J3937D01*
G01X107993D02*
G03Y472441I0J-3937D01*
G01X77283Y952756D02*
G03Y960630I0J3937D01*
G01X107993D02*
G03Y952756I0J-3937D01*
G01Y960630D02*
X304843D01*
G01X335552Y0D02*
G03Y-7874I0J-3937D01*
G01X304843D02*
G03Y0I0J3937D01*
G01X335552Y-7874D02*
X532402D01*
G01X304843Y472441D02*
G03Y480315I0J3937D01*
G01X335552D02*
G03Y472441I0J-3937D01*
G01Y960630D02*
G03Y952756I0J-3937D01*
G01X304843D02*
G03Y960630I0J3937D01*
G01X335552D02*
X532402D01*
G01Y-7874D02*
G03Y0I0J3937D01*
G01X563111D02*
G03Y-7874I0J-3937D01*
G01D02*
X725552D01*
G01X627391Y353740D02*
X545906D01*
G01X627391Y378543D02*
X545906D01*
G01X541969Y357677D02*
Y374606D01*
G01Y357677D02*
G03X545906Y353740I3937J0D01*
G01Y378543D02*
G03X541969Y374606I0J-3937D01*
G01X545906Y378543D02*
G03X541969Y374606I0J-3937D01*
G01Y357677D02*
G03X545906Y353740I3937J0D01*
G01X541969Y357677D02*
G03X545906Y353740I3937J0D01*
G01Y378543D02*
G03X541969Y374606I0J-3937D01*
G01Y357677D02*
Y374606D01*
G01Y357677D02*
Y374606D01*
G01X627391Y378543D02*
X545906D01*
G01X627391D02*
X545906D01*
G01X627391Y353740D02*
X545906D01*
G01X627391D02*
X545906D01*
G01X532402Y472441D02*
G03Y480315I0J3937D01*
G01X563111D02*
G03Y472441I0J-3937D01*
G01X541969Y837992D02*
G03X545906Y834055I3937J0D01*
G01X541969Y837992D02*
G03X545906Y834055I3937J0D01*
G01X541969Y837992D02*
Y854921D01*
G01Y837992D02*
Y854921D01*
G01X627391Y834055D02*
X545906D01*
G01X627391D02*
X545906D01*
G01Y858858D02*
G03X541969Y854921I0J-3937D01*
G01X545906Y858858D02*
G03X541969Y854921I0J-3937D01*
G01X627391Y858858D02*
X545906D01*
G01X627391D02*
X545906D01*
G01X532402Y952756D02*
G03Y960630I0J3937D01*
G01X563111D02*
G03Y952756I0J-3937D01*
G01Y960630D02*
X725552D01*
G01X636457Y132035D02*
X624646D01*
G01X620709Y135972D02*
G03X622675Y132564I3937J0D01*
G01X622709Y132545D02*
G03X624646Y132035I1938J3427D01*
G01X622675Y132564D02*
G03X622709Y132545I1937J3427D01*
G01X622675Y132564D02*
G03X624646Y132035I1971J3409D01*
G01X620709Y135972D02*
G03X622675Y132564I3937J0D01*
G01X620709Y135972D02*
G03X622708Y132545I3937J0D01*
G01X620709Y135972D02*
Y312846D01*
G01Y135972D02*
Y312846D01*
G01X622675Y132564D02*
G03X624646Y132035I1971J3409D01*
G01X622708Y132545D02*
G03X624646Y132035I1938J3427D01*
G01X620709Y135972D02*
G03X622675Y132564I3937J0D01*
G01X620709Y135972D02*
G03X622708Y132545I3937J0D01*
G01X620709Y135972D02*
Y312846D01*
G01Y135972D02*
Y312846D01*
G01X636457Y132035D02*
X624646D01*
G01X636457D02*
X624646D01*
G01X636457Y316783D02*
X624646D01*
G01X622675Y316255D02*
G03X620709Y312846I1971J-3408D01*
G01X624646Y316783D02*
G03X622709Y316274I-1J-3937D01*
G01D02*
G03X622675Y316255I1904J-3446D01*
G01X624646Y316783D02*
G03X622675Y316255I-1J-3937D01*
G01D02*
G03X620709Y312846I1971J-3408D01*
G01X622708Y316274D02*
G03X620709Y312846I1938J-3427D01*
G01X624646Y316783D02*
G03X622675Y316255I-1J-3937D01*
G01X624646Y316783D02*
G03X622708Y316274I-2J-3937D01*
G01X622675Y316255D02*
G03X620709Y312846I1971J-3408D01*
G01X622708Y316274D02*
G03X620709Y312846I1938J-3427D01*
G01X636457Y316783D02*
X624646D01*
G01X636457D02*
X624646D01*
G01X620709Y312657D02*
Y311161D01*
G01X629575Y379204D02*
X638641Y385248D01*
G01Y347035D02*
X629575Y353079D01*
G01D02*
G03X627391Y353740I-2184J-3276D01*
G01Y378543D02*
G03X629575Y379204I0J3937D01*
G01X627391Y378543D02*
G03X629574Y379205I-2J3937D01*
G01X627391Y378543D02*
G03X629574Y379205I-2J3937D01*
G01Y353079D02*
G03X627391Y353740I-2184J-3276D01*
G01X629574Y353079D02*
G03X627391Y353740I-2184J-3276D01*
G01X638641Y347035D02*
X629574Y353079D01*
G01X638641Y347035D02*
X629574Y353079D01*
G01Y379204D02*
X638641Y385248D01*
G01X629574Y379204D02*
X638641Y385248D01*
G01X622675Y612879D02*
G03X624646Y612350I1971J3409D01*
G01X622708Y612860D02*
G03X624646Y612350I1938J3427D01*
G01X620709Y616287D02*
G03X622675Y612879I3937J0D01*
G01X620709Y616287D02*
G03X622708Y612860I3937J0D01*
G01X620709Y616287D02*
Y793161D01*
G01Y616287D02*
Y793161D01*
G01X636457Y612350D02*
X624646D01*
G01X636457D02*
X624646D01*
G01Y797098D02*
G03X622675Y796570I-1J-3937D01*
G01X624646Y797098D02*
G03X622708Y796589I-2J-3937D01*
G01X622675Y796570D02*
G03X620709Y793161I1971J-3408D01*
G01X622708Y796589D02*
G03X620709Y793161I1938J-3427D01*
G01X636457Y797098D02*
X624646D01*
G01X636457D02*
X624646D01*
G01X629574Y833394D02*
G03X627391Y834055I-2184J-3276D01*
G01X629574Y833394D02*
G03X627391Y834055I-2184J-3276D01*
G01X638641Y827350D02*
X629574Y833394D01*
G01X638641Y827350D02*
X629574Y833394D01*
G01X627391Y858858D02*
G03X629574Y859520I-2J3937D01*
G01X627391Y858858D02*
G03X629574Y859520I-2J3937D01*
G01D02*
X638641Y865563D01*
G01X629574Y859520D02*
X638641Y865563D01*
G01X640394Y128098D02*
Y3937D01*
G01X636457Y0D02*
G03X640394Y3937I0J3937D01*
G01Y128098D02*
Y3937D01*
G01Y128098D02*
Y3937D01*
G01X648267Y34437D02*
G03X640393I-3937J0D01*
G01X648266Y3937D02*
G03X652203Y0I3937J0D01*
G01X648266Y3937D02*
G03X652203Y0I3937J0D01*
G01X648266Y3937D02*
Y83917D01*
G01Y3937D02*
Y83917D01*
G01X1284723Y0D02*
X652203D01*
G01X1284723D02*
X652203D01*
G01X636457D02*
G03X640394Y3937I0J3937D01*
G01X636457Y0D02*
G03X640394Y3937I0J3937D01*
G01Y112350D02*
Y3937D01*
G01Y112350D02*
Y3937D01*
G01X640393Y65146D02*
G03X648267I3937J0D01*
G01X650019Y87193D02*
G03X648266Y83917I2185J-3276D01*
G01X661269Y93898D02*
G03X659085Y93237I0J-3937D01*
G01X661269Y93898D02*
G03X659085Y93237I0J-3937D01*
G01X650019Y87193D02*
G03X648266Y83917I2185J-3276D01*
G01X661269Y93898D02*
X742754D01*
G01X661269D02*
X742754D01*
G01X659085Y93237D02*
X650019Y87193D01*
G01X659085Y93237D02*
X650019Y87193D01*
G01X640394Y128098D02*
G03X636457Y132035I-3937J0D01*
G01X664014Y155657D02*
G03X665985Y156186I0J3938D01*
G01X652203Y155657D02*
G03X648266Y151720I0J-3937D01*
G01X652203Y155657D02*
G03X648266Y151720I0J-3937D01*
G01X664014Y155657D02*
G03X665952Y156167I0J3937D01*
G01X665985Y156186D02*
G03X667951Y159594I-1971J3408D01*
G01X665952Y156167D02*
G03X667951Y159594I-1938J3427D01*
G01X648266Y128682D02*
Y151720D01*
G01Y128682D02*
Y151720D01*
G01X667951Y336469D02*
Y159594D01*
G01Y336469D02*
Y159594D01*
G01X652203Y155657D02*
X664014D01*
G01X652203D02*
X664014D01*
G01X640394Y128098D02*
G03X636457Y132035I-3937J0D01*
G01X640394Y128098D02*
G03X636457Y132035I-3937J0D01*
G01X659085Y119362D02*
G03X661269Y118701I2184J3276D01*
G01X648266Y128682D02*
G03X650019Y125406I3937J0D01*
G01X648266Y128682D02*
G03X650019Y125406I3937J0D01*
G01X659085Y119362D02*
G03X661269Y118701I2184J3276D01*
G01X650019Y125406D02*
X659085Y119362D01*
G01X650019Y125406D02*
X659085Y119362D01*
G01X661269Y118701D02*
X742754D01*
G01X661269D02*
X742754D01*
G01X640394Y343759D02*
Y320720D01*
G01X636457Y316783D02*
G03X640394Y320720I0J3937D01*
G01X636457Y316783D02*
G03X640394Y320720I0J3937D01*
G01X636457Y316783D02*
G03X640394Y320720I0J3937D01*
G01Y343759D02*
Y320720D01*
G01Y343759D02*
Y320720D01*
G01Y388524D02*
Y421048D01*
G01Y343759D02*
G03X638641Y347035I-3937J0D01*
G01Y385248D02*
G03X640394Y388524I-2184J3276D01*
G01X665985Y339877D02*
G03X664014Y340406I-1971J-3409D01*
G01X648266Y344343D02*
G03X652203Y340406I3937J0D01*
G01X665952Y339896D02*
G03X664014Y340406I-1938J-3427D01*
G01X648266Y344343D02*
G03X652203Y340406I3937J0D01*
G01X667951Y336469D02*
G03X665985Y339877I-3937J0D01*
G01X667951Y336469D02*
G03X665952Y339896I-3937J0D01*
G01X648266Y344343D02*
Y468504D01*
G01Y344343D02*
Y468504D01*
G01X652203Y340406D02*
X664014D01*
G01X652203D02*
X664014D01*
G01X648266Y360091D02*
Y468504D01*
G01Y360091D02*
Y468504D01*
G01X638641Y385248D02*
G03X640394Y388524I-2185J3276D01*
G01X638641Y385248D02*
G03X640394Y388524I-2185J3276D01*
G01Y343759D02*
G03X638641Y347035I-3937J0D01*
G01X640394Y343759D02*
G03X638641Y347035I-3937J0D01*
G01X640394Y468504D02*
Y388524D01*
G01Y468504D02*
Y388524D01*
G01Y421048D02*
Y445094D01*
G01D02*
Y468504D01*
G01X640393Y438004D02*
G03X648267I3937J0D01*
G01Y407295D02*
G03X640393I-3937J0D01*
G01X640394Y468504D02*
G03X636457Y472441I-3937J0D01*
G01X640394Y608413D02*
Y484252D01*
G01Y608413D02*
Y484252D01*
G01X652203Y472441D02*
G03X648266Y468504I0J-3937D01*
G01X652203Y472441D02*
G03X648266Y468504I0J-3937D01*
G01X652203Y472441D02*
X1284723D01*
G01X652203D02*
X1284723D01*
G01X648266Y484252D02*
G03X652203Y480315I3937J0D01*
G01X648266Y484252D02*
G03X652203Y480315I3937J0D01*
G01X648266Y484252D02*
Y564231D01*
G01Y484252D02*
Y564231D01*
G01X1284723Y480315D02*
X652203D01*
G01X1284723D02*
X652203D01*
G01X636457D02*
G03X640394Y484252I0J3937D01*
G01X636457Y480315D02*
G03X640394Y484252I0J3937D01*
G01Y592665D02*
Y484252D01*
G01Y592665D02*
Y484252D01*
G01Y468504D02*
G03X636457Y472441I-3937J0D01*
G01X640394Y468504D02*
G03X636457Y472441I-3937J0D01*
G01X648267Y514753D02*
G03X640393I-3937J0D01*
G01Y545462D02*
G03X648267I3937J0D01*
G01X648266Y608997D02*
Y632035D01*
G01Y608997D02*
Y632035D01*
G01X640394Y608413D02*
G03X636457Y612350I-3937J0D01*
G01X640394Y608413D02*
G03X636457Y612350I-3937J0D01*
G01X650019Y567507D02*
G03X648266Y564231I2184J-3276D01*
G01X661269Y574213D02*
G03X659085Y573552I0J-3937D01*
G01X661269Y574213D02*
G03X659085Y573552I0J-3937D01*
G01X650019Y567507D02*
G03X648266Y564231I2184J-3276D01*
G01X659085Y599677D02*
G03X661269Y599016I2184J3276D01*
G01X648266Y608997D02*
G03X650019Y605721I3937J0D01*
G01X648266Y608997D02*
G03X650019Y605721I3937J0D01*
G01X659085Y599677D02*
G03X661269Y599016I2184J3276D01*
G01X650019Y605721D02*
X659085Y599677D01*
G01X650019Y605721D02*
X659085Y599677D01*
G01X661269Y574213D02*
X742754D01*
G01X661269D02*
X742754D01*
G01X661269Y599016D02*
X742754D01*
G01X661269D02*
X742754D01*
G01X659085Y573552D02*
X650019Y567507D01*
G01X659085Y573552D02*
X650019Y567507D01*
G01X664014Y635972D02*
G03X665985Y636501I0J3938D01*
G01X652203Y635972D02*
G03X648266Y632035I0J-3937D01*
G01X652203Y635972D02*
G03X648266Y632035I0J-3937D01*
G01X664014Y635972D02*
G03X665952Y636482I0J3937D01*
G01X665985Y636501D02*
G03X667951Y639909I-1971J3408D01*
G01X665952Y636482D02*
G03X667951Y639909I-1938J3427D01*
G01Y816783D02*
Y639909D01*
G01Y816783D02*
Y639909D01*
G01X652203Y635972D02*
X664014D01*
G01X652203D02*
X664014D01*
G01X665985Y820192D02*
G03X664014Y820720I-1970J-3409D01*
G01X648266Y824657D02*
G03X652203Y820720I3937J0D01*
G01X665952Y820211D02*
G03X664014Y820720I-1936J-3428D01*
G01X648266Y824657D02*
G03X652203Y820720I3937J0D01*
G01X667951Y816783D02*
G03X665985Y820192I-3937J1D01*
G01X667951Y816783D02*
G03X665952Y820211I-3937J1D01*
G01X648266Y824657D02*
Y948819D01*
G01Y824657D02*
Y948819D01*
G01X652203Y820720D02*
X664014D01*
G01X652203D02*
X664014D01*
G01X636457Y797098D02*
G03X640394Y801035I0J3937D01*
G01X636457Y797098D02*
G03X640394Y801035I0J3937D01*
G01Y824074D02*
Y801035D01*
G01Y824074D02*
Y801035D01*
G01X648266Y840406D02*
Y948819D01*
G01Y840406D02*
Y948819D01*
G01X640394Y824074D02*
G03X638641Y827350I-3938J0D01*
G01X640394Y824074D02*
G03X638641Y827350I-3938J0D01*
G01X648267Y887611D02*
G03X640393I-3937J0D01*
G01X638641Y865563D02*
G03X640394Y868839I-2185J3276D01*
G01X638641Y865563D02*
G03X640394Y868839I-2185J3276D01*
G01Y948819D02*
Y868839D01*
G01Y948819D02*
Y868839D01*
G01X640393Y918320D02*
G03X648267I3937J0D01*
G01X652203Y952756D02*
G03X648266Y948819I0J-3937D01*
G01X652203Y952756D02*
G03X648266Y948819I0J-3937D01*
G01X652203Y952756D02*
X1284723D01*
G01X652203D02*
X1284723D01*
G01X640394Y948819D02*
G03X636457Y952756I-3937J0D01*
G01X640394Y948819D02*
G03X636457Y952756I-3937J0D01*
G01X725552Y-7874D02*
G03Y0I0J3937D01*
G01X742754Y93898D02*
G03X746691Y97835I0J3937D01*
G01X742754Y93898D02*
G03X746691Y97835I0J3937D01*
G01Y114764D02*
Y97835D01*
G01Y114764D02*
Y97835D01*
G01Y114764D02*
G03X742754Y118701I-3937J0D01*
G01X746691Y114764D02*
G03X742754Y118701I-3937J0D01*
G01X725552Y472441D02*
G03Y480315I0J3937D01*
G01X742754Y574213D02*
G03X746691Y578150I0J3937D01*
G01Y595079D02*
G03X742754Y599016I-3937J0D01*
G01X746691Y595079D02*
G03X742754Y599016I-3937J0D01*
G01Y574213D02*
G03X746691Y578150I0J3937D01*
G01Y595079D02*
Y578150D01*
G01Y595079D02*
Y578150D01*
G01X725552Y952756D02*
G03Y960630I0J3937D01*
G01X953111Y-7874D02*
X756261D01*
G01Y0D02*
G03Y-7874I0J-3937D01*
G01Y480315D02*
G03Y472441I0J-3937D01*
G01Y960630D02*
G03Y952756I0J-3937D01*
G01X953111Y960630D02*
X756261D01*
G01X953111Y-7874D02*
G03Y0I0J3937D01*
G01Y472441D02*
G03Y480315I0J3937D01*
G01Y952756D02*
G03Y960630I0J3937D01*
G01X1180670Y-7874D02*
X983820D01*
G01Y0D02*
G03Y-7874I0J-3937D01*
G01Y480315D02*
G03Y472441I0J-3937D01*
G01Y960630D02*
G03Y952756I0J-3937D01*
G01X1180670Y960630D02*
X983820D01*
G01X1180670Y-7874D02*
G03Y0I0J3937D01*
G01Y472441D02*
G03Y480315I0J3937D01*
G01Y952756D02*
G03Y960630I0J3937D01*
G01X1211380Y0D02*
G03Y-7874I0J-3937D01*
G01D02*
X1284723D01*
G01X1211380Y480315D02*
G03Y472441I0J-3937D01*
G01Y960630D02*
G03Y952756I0J-3937D01*
G01Y960630D02*
X1284723D01*
G01X1317968Y-19685D02*
G03X1331968Y-5685I0J14000D01*
G01X1296534Y45847D02*
G03X1288660I-3937J0D01*
G01X1296534Y3937D02*
Y45847D01*
G01X1284723Y-7874D02*
G03X1296534Y3937I0J11811D01*
G01X1284723Y0D02*
G03X1288660Y3937I0J3937D01*
G01X1284723Y0D02*
G03X1288660Y3937I0J3937D01*
G01Y102559D02*
Y3937D01*
G01Y102559D02*
Y3937D01*
G01Y71044D02*
G03X1296534I3937J0D01*
G01Y98622D02*
Y71044D01*
G01X1331968Y98622D02*
X1296534D01*
G01X1292597Y106496D02*
G03X1288660Y102559I0J-3937D01*
G01X1292597Y106496D02*
G03X1288660Y102559I0J-3937D01*
G01X1292597Y106496D02*
X1326061D01*
G01X1292597D02*
X1326061D01*
G01X1290038Y180394D02*
G03Y177638I0J-1378D01*
G01Y180394D02*
G03Y177638I0J-1378D01*
G01X1326061D02*
X1290038D01*
G01X1326061D02*
X1290038D01*
G01X1301258Y180394D02*
X1290038D01*
G01X1326061D02*
X1290038D01*
G01X1301258D02*
X1326061D01*
G01X1296534Y369409D02*
Y396985D01*
G01X1331968Y369409D02*
X1296534D01*
G01X1288660Y365472D02*
G03X1292597Y361535I3937J0D01*
G01X1288660Y365472D02*
G03X1292597Y361535I3937J0D01*
G01X1326061D02*
X1292597D01*
G01X1326061D02*
X1292597D01*
G01X1288660Y468504D02*
Y365472D01*
G01Y468504D02*
Y365472D01*
G01Y422182D02*
G03X1296534I3937J0D01*
G01Y526162D02*
Y422182D01*
G01Y396985D02*
G03X1288660I-3937J0D01*
G01Y468504D02*
G03X1284723Y472441I-3937J0D01*
G01X1288660Y468504D02*
G03X1284723Y472441I-3937J0D01*
G01Y480315D02*
G03X1288660Y484252I0J3937D01*
G01X1284723Y480315D02*
G03X1288660Y484252I0J3937D01*
G01Y582874D02*
Y484252D01*
G01Y582874D02*
Y484252D01*
G01X1296534Y526162D02*
G03X1288660I-3937J0D01*
G01Y551359D02*
G03X1296534I3937J0D01*
G01Y578937D02*
Y551359D01*
G01X1331968Y578937D02*
X1296534D01*
G01X1292597Y586811D02*
G03X1288660Y582874I0J-3937D01*
G01X1292597Y586811D02*
G03X1288660Y582874I0J-3937D01*
G01X1292597Y586811D02*
X1326061D01*
G01X1292597D02*
X1326061D01*
G01X1290038Y660709D02*
G03Y657953I0J-1378D01*
G01Y660709D02*
G03Y657953I0J-1378D01*
G01X1326061D02*
X1290038D01*
G01X1326061D02*
X1290038D01*
G01X1301258Y660709D02*
X1290038D01*
G01X1326061D02*
X1290038D01*
G01X1301258D02*
X1326061D01*
G01X1288660Y845787D02*
G03X1292597Y841850I3937J0D01*
G01X1288660Y845787D02*
G03X1292597Y841850I3937J0D01*
G01X1326061D02*
X1292597D01*
G01X1326061D02*
X1292597D01*
G01X1331968Y849724D02*
X1296534D01*
G01X1288660Y902497D02*
G03X1296534I3937J0D01*
G01Y948819D02*
Y902497D01*
G01Y877296D02*
G03X1288660I-3937J0D01*
G01X1296534Y849724D02*
Y877300D01*
G01X1288660Y948819D02*
Y845787D01*
G01Y948819D02*
Y845787D01*
G01X1296534Y948819D02*
G03X1284723Y960630I-11811J0D01*
G01X1288660Y948819D02*
G03X1284723Y952756I-3937J0D01*
G01X1288660Y948819D02*
G03X1284723Y952756I-3937J0D01*
G01X1331968Y958441D02*
G03X1317968Y972441I-14000J0D01*
G01X1331968Y-5685D02*
Y98622D01*
G01X1326061Y106496D02*
X1331967Y112402D01*
G01X1326061Y106496D02*
X1329998Y110433D01*
G01X1331967Y112402D02*
Y171732D01*
G01X1329998Y173701D02*
X1326061Y177638D01*
G01X1331967Y171732D02*
X1326061Y177638D01*
G01Y180394D02*
X1331967Y186299D01*
G01X1326061Y180394D02*
X1329998Y184331D01*
G01X1331967Y186299D02*
Y355630D01*
G01X1331968Y578937D02*
Y369409D01*
G01X1329998Y357598D02*
X1326061Y361535D01*
G01X1331967Y355630D02*
X1326061Y361535D01*
G01Y586811D02*
X1331967Y592717D01*
G01X1326061Y586811D02*
X1329998Y590748D01*
G01X1331967Y592717D02*
Y652047D01*
G01X1329998Y654016D02*
X1326061Y657953D01*
G01X1331967Y652047D02*
X1326061Y657953D01*
G01Y660709D02*
X1331967Y666614D01*
G01X1326061Y660709D02*
X1329998Y664646D01*
G01X1331967Y666614D02*
Y835945D01*
G01X1329998Y837913D02*
X1326061Y841850D01*
G01X1331967Y835945D02*
X1326061Y841850D01*
G01X1331968Y958441D02*
Y849724D01*
M02*
